# S9S_MB_2U (Grand Teton) — schematic netlist excerpt (pin names and nets, part order shuffled) for the footprints in the layout excerpt that follows; sources: Cadence DE-HDL packaged netlist, KiCad conversion of 03242023_DA0F0TMBIJ0_F0T_Motherboard_J_brd_V01_OCP.brd

R1444  Q_RES  33.2 1% CHIP  pkg 0402LF  page 222 : A = PWRGD_P1V8_PCH_AUX ; B = PWRGD_P1V8_PCH_AUX_PLD
C1878  Q_CAP  0.1UF 25V 10% X7R  pkg 0402  page 165 : A = P3V3_AUX ; B = GND

(kicad_pcb
	(version 20260206)
	(generator "pcbnew")
	(generator_version "10.0")
	(general
		(thickness 1.6)
		(legacy_teardrops no)
	)
	(paper "A4")
	(title_block
		(title "03242023_DA0F0TMBIJ0_F0T_Motherboard_J_brd_V01_OCP.brd")
		(comment 1 "Grand Teton / footprints 1465-1466 of 6105")
	)
	(layers
		(0 "F.Cu" signal "TOP")
		(4 "In1.Cu" signal "GND")
		(6 "In2.Cu" signal "IN1")
		(8 "In3.Cu" signal "GND1")
		(10 "In4.Cu" signal "IN2")
		(12 "In5.Cu" signal "GND2")
		(14 "In6.Cu" signal "IN3")
		(16 "In7.Cu" signal "GND3")
		(18 "In8.Cu" signal "VCC")
		(20 "In9.Cu" signal "VCC1")
		(22 "In10.Cu" signal "GND4")
		(24 "In11.Cu" signal "IN4")
		(26 "In12.Cu" signal "GND5")
		(28 "In13.Cu" signal "IN5")
		(30 "In14.Cu" signal "GND6")
		(32 "In15.Cu" signal "IN6")
		(34 "In16.Cu" signal "GND7")
		(2 "B.Cu" signal "BOTTOM")
		(9 "F.Adhes" user "F.Adhesive")
		(11 "B.Adhes" user "B.Adhesive")
		(13 "F.Paste" user "Package Geometry/Pastemask Top")
		(15 "B.Paste" user "Package Geometry/Pastemask Bottom")
		(5 "F.SilkS" user "Ref Des/Silkscreen Top")
		(7 "B.SilkS" user "Ref Des/Silkscreen Bottom")
		(1 "F.Mask" user "Board Geometry/Soldermask Top")
		(3 "B.Mask" user "Board Geometry/Soldermask Bottom")
		(17 "Dwgs.User" user "User.Drawings")
		(19 "Cmts.User" user "User.Comments")
		(21 "Eco1.User" user "User.Eco1")
		(23 "Eco2.User" user "User.Eco2")
		(25 "Edge.Cuts" user "Board Geometry/Outline")
		(27 "Margin" user)
		(31 "F.CrtYd" user "Package Geometry/Place Bound Top")
		(29 "B.CrtYd" user "Package Geometry/Place Bound Bottom")
		(35 "F.Fab" user "Ref Des/Assembly Top")
		(33 "B.Fab" user "Ref Des/Assembly Bottom")
	)
	(footprint ""
		(layer "F.Cu")
		(at 149.81428 -32.929068)
		(property "Reference" "C1878"
			(at 0 0 0)
			(layer "F.SilkS")
			(hide yes)
			(effects
				(font
					(size 1.27 1.27)
				)
			)
		)
		(property "Value" ""
			(at 0 0 0)
			(layer "F.Fab")
			(effects
				(font
					(size 1.27 1.27)
				)
			)
		)
		(duplicate_pad_numbers_are_jumpers no)
		(fp_line
			(start -0.7874 -0.4064)
			(end 0.7874 -0.4064)
			(stroke
				(width 0.1524)
				(type default)
			)
			(layer "F.SilkS")
		)
		(fp_line
			(start -0.7874 0.4064)
			(end -0.7874 -0.4064)
			(stroke
				(width 0.1524)
				(type default)
			)
			(layer "F.SilkS")
		)
		(fp_line
			(start 0.7874 -0.4064)
			(end 0.7874 0.4064)
			(stroke
				(width 0.1524)
				(type default)
			)
			(layer "F.SilkS")
		)
		(fp_line
			(start 0.7874 0.4064)
			(end -0.7874 0.4064)
			(stroke
				(width 0.1524)
				(type default)
			)
			(layer "F.SilkS")
		)
		(fp_line
			(start -0.67945 -0.305054)
			(end -0.12065 -0.305054)
			(stroke
				(width 0.1)
				(type default)
			)
			(layer "F.Fab")
		)
		(fp_line
			(start -0.67945 0.3048)
			(end -0.67945 -0.305054)
			(stroke
				(width 0.1)
				(type default)
			)
			(layer "F.Fab")
		)
		(fp_line
			(start -0.12065 -0.305054)
			(end -0.12065 -0.2794)
			(stroke
				(width 0.1)
				(type default)
			)
			(layer "F.Fab")
		)
		(fp_line
			(start -0.12065 -0.2794)
			(end 0.12065 -0.2794)
			(stroke
				(width 0.1)
				(type default)
			)
			(layer "F.Fab")
		)
		(fp_line
			(start -0.12065 0.2794)
			(end -0.12065 0.3048)
			(stroke
				(width 0.1)
				(type default)
			)
			(layer "F.Fab")
		)
		(fp_line
			(start -0.12065 0.3048)
			(end -0.67945 0.3048)
			(stroke
				(width 0.1)
				(type default)
			)
			(layer "F.Fab")
		)
		(fp_line
			(start 0.120396 0.2794)
			(end -0.12065 0.2794)
			(stroke
				(width 0.1)
				(type default)
			)
			(layer "F.Fab")
		)
		(fp_line
			(start 0.120396 0.3048)
			(end 0.120396 0.2794)
			(stroke
				(width 0.1)
				(type default)
			)
			(layer "F.Fab")
		)
		(fp_line
			(start 0.12065 -0.3048)
			(end 0.67945 -0.3048)
			(stroke
				(width 0.1)
				(type default)
			)
			(layer "F.Fab")
		)
		(fp_line
			(start 0.12065 -0.2794)
			(end 0.12065 -0.3048)
			(stroke
				(width 0.1)
				(type default)
			)
			(layer "F.Fab")
		)
		(fp_line
			(start 0.67945 -0.3048)
			(end 0.67945 0.3048)
			(stroke
				(width 0.1)
				(type default)
			)
			(layer "F.Fab")
		)
		(fp_line
			(start 0.67945 0.3048)
			(end 0.120396 0.3048)
			(stroke
				(width 0.1)
				(type default)
			)
			(layer "F.Fab")
		)
		(pad "1" smd circle
			(at -0.40005 0)
			(size 0 0)
			(layers "F.Cu" "F.Mask" "F.Paste")
			(net "P3V3_AUX")
		)
		(pad "2" smd circle
			(at 0.40005 0)
			(size 0 0)
			(layers "F.Cu" "F.Mask" "F.Paste")
			(net "GND")
		)
	)
	(footprint ""
		(layer "F.Cu")
		(at 174.04588 -126.964948 -90)
		(property "Reference" "R1444"
			(at 0 0 270)
			(layer "F.SilkS")
			(hide yes)
			(effects
				(font
					(size 1.27 1.27)
				)
			)
		)
		(property "Value" ""
			(at 0 0 270)
			(layer "F.Fab")
			(effects
				(font
					(size 1.27 1.27)
				)
			)
		)
		(duplicate_pad_numbers_are_jumpers no)
		(fp_line
			(start -0.7874 0.4064)
			(end -0.7874 -0.4064)
			(stroke
				(width 0.1524)
				(type default)
			)
			(layer "F.SilkS")
		)
		(fp_line
			(start 0.7874 0.4064)
			(end -0.7874 0.4064)
			(stroke
				(width 0.1524)
				(type default)
			)
			(layer "F.SilkS")
		)
		(fp_line
			(start -0.7874 -0.4064)
			(end 0.7874 -0.4064)
			(stroke
				(width 0.1524)
				(type default)
			)
			(layer "F.SilkS")
		)
		(fp_line
			(start 0.7874 -0.4064)
			(end 0.7874 0.4064)
			(stroke
				(width 0.1524)
				(type default)
			)
			(layer "F.SilkS")
		)
		(fp_line
			(start -0.67945 0.3048)
			(end -0.67945 -0.305054)
			(stroke
				(width 0.1)
				(type default)
			)
			(layer "F.Fab")
		)
		(fp_line
			(start -0.12065 0.3048)
			(end -0.67945 0.3048)
			(stroke
				(width 0.1)
				(type default)
			)
			(layer "F.Fab")
		)
		(fp_line
			(start 0.120396 0.3048)
			(end 0.120396 0.2794)
			(stroke
				(width 0.1)
				(type default)
			)
			(layer "F.Fab")
		)
		(fp_line
			(start 0.67945 0.3048)
			(end 0.120396 0.3048)
			(stroke
				(width 0.1)
				(type default)
			)
			(layer "F.Fab")
		)
		(fp_line
			(start -0.12065 0.2794)
			(end -0.12065 0.3048)
			(stroke
				(width 0.1)
				(type default)
			)
			(layer "F.Fab")
		)
		(fp_line
			(start 0.120396 0.2794)
			(end -0.12065 0.2794)
			(stroke
				(width 0.1)
				(type default)
			)
			(layer "F.Fab")
		)
		(fp_line
			(start -0.12065 -0.2794)
			(end 0.12065 -0.2794)
			(stroke
				(width 0.1)
				(type default)
			)
			(layer "F.Fab")
		)
		(fp_line
			(start 0.12065 -0.2794)
			(end 0.12065 -0.3048)
			(stroke
				(width 0.1)
				(type default)
			)
			(layer "F.Fab")
		)
		(fp_line
			(start 0.12065 -0.3048)
			(end 0.67945 -0.3048)
			(stroke
				(width 0.1)
				(type default)
			)
			(layer "F.Fab")
		)
		(fp_line
			(start 0.67945 -0.3048)
			(end 0.67945 0.3048)
			(stroke
				(width 0.1)
				(type default)
			)
			(layer "F.Fab")
		)
		(fp_line
			(start -0.67945 -0.305054)
			(end -0.12065 -0.305054)
			(stroke
				(width 0.1)
				(type default)
			)
			(layer "F.Fab")
		)
		(fp_line
			(start -0.12065 -0.305054)
			(end -0.12065 -0.2794)
			(stroke
				(width 0.1)
				(type default)
			)
			(layer "F.Fab")
		)
		(pad "1" smd circle
			(at -0.40005 0 270)
			(size 0 0)
			(layers "F.Cu" "F.Mask" "F.Paste")
			(net "PWRGD_P1V8_PCH_AUX")
		)
		(pad "2" smd circle
			(at 0.40005 0 270)
			(size 0 0)
			(layers "F.Cu" "F.Mask" "F.Paste")
			(net "PWRGD_P1V8_PCH_AUX_PLD")
		)
	)
)
